FILE_TYPE = MULTI_PHYS_TABLE;

PART 'POWERMOS_3P_PCH'
CLASS=DISCRETE

{========================================================================================}
:CLS_PN             = JEDEC_TYPE      | ALT_SYMBOLS       | DESCRIPTION                                                             | CPN_STATUS ;
{========================================================================================}
 'G121-10125-01'    = 'SOT23_V1'      | '(SOT23_V1)'      | 'FET,IRLML6402,P-CH,20V,0.065OHM,3.7A,SOT23'                            | ''        
 'G121-10009-01'    = 'SOT23_V1'      | '(SOT23_V1)'      | 'FET, IRLML6302,P-CH, 20V, 0.6OHM, 0.6A, SOT23'                         | ''        
 'G121-10139-01'    = 'SOT23_V1'      | '(SOT23_V1)'      | 'FET,P-CH,IRLML5203,-30V,0.098OHM,-3A,SOT-23'                           | ''        
 'G121-10140-01'    = 'SOT23_V1'      | '(SOT23_V1)'      | 'FET,P-CH,DMP4065S,-40V,0.08OHM,-3.4A,SOT-23'                           | ''        
 'G121-10180-01'    = 'SOT23_V1'      | '(SOT23_V1)'      | 'FET, P-CH, 40V, 0.077OHM, 4.4A, SOT-23'                                | 'OBSOLETE'
 'G121-10029-01'    = 'SOT23_V1'      | '(SOT23_V1)'      | 'FET,MOSFET,P-CH,-30V,0.062OHM,-4.6A,SOT-23'                            | ''        
 'G121-10195-01'    = 'SOT23_V1_H043' | '(SOT23_V1_H043)' | 'FET,MOSFET P-CH,VDSS -20V,RDSON 0.6OHM@VGD-4.5V,ID -0.92A@25C,SOT23-3' | ''        
 'A121-00017-IB'    = 'SOT23_V1'      | '(SOT23_V1)'      | 'FET,MOSFET,P,30V,0.086R/3.1A,SOT23'                                    | ''        
 'G121-10203-01'    = 'SOT23_V1_H043' | '(SOT23_V1_H043)' | 'FET,P-CH,50V,10OHM,0.13A,SOT23'                                        | ''        
 'G121-10216-01'    = 'SOT23_V1_H045' | '(SOT23_V1_H045)' | 'FET,P-CH,30V,65MOHM,3.8A,SOT23'                                        | ''        

END_PART

END.

